(kicad_pcb
	(version 20241229)
	(generator "pcbnew")
	(generator_version "9.0")
	(general
		(thickness 1.294)
		(legacy_teardrops no)
	)
	(paper "A3")
	(title_block
		(title "Kintex 410T devboard")
		(date "2024-04-03")
		(rev "1.1.2")
		(comment 9 "footprints 922-926 of 975")
	)
	(layers
		(0 "F.Cu" mixed)
		(4 "In1.Cu" power)
		(6 "In2.Cu" power)
		(8 "In3.Cu" mixed)
		(10 "In4.Cu" power)
		(12 "In5.Cu" mixed)
		(14 "In6.Cu" power)
		(16 "In7.Cu" mixed)
		(18 "In8.Cu" power)
		(2 "B.Cu" mixed)
		(9 "F.Adhes" user "F.Adhesive")
		(11 "B.Adhes" user "B.Adhesive")
		(13 "F.Paste" user)
		(15 "B.Paste" user)
		(5 "F.SilkS" user "F.Silkscreen")
		(7 "B.SilkS" user "B.Silkscreen")
		(1 "F.Mask" user)
		(3 "B.Mask" user)
		(17 "Dwgs.User" user "User.Drawings")
		(19 "Cmts.User" user "User.Comments")
		(21 "Eco1.User" user "User.Eco1")
		(23 "Eco2.User" user "User.Eco2")
		(25 "Edge.Cuts" user)
		(27 "Margin" user)
		(31 "F.CrtYd" user "F.Courtyard")
		(29 "B.CrtYd" user "B.Courtyard")
		(35 "F.Fab" user)
		(33 "B.Fab" user)
	)
	(footprint "antmicro-footprints:C_0402_1005Metric"
		(layer "B.Cu")
		(at 251.351 135.5 -90)
		(descr "Capacitor SMD 0402")
		(tags "capacitor SMD 0402")
		(property "Reference" "C211"
			(at 0.35 0.326 180)
			(layer "B.SilkS")
			(effects
				(font
					(size 0.7 0.7)
					(thickness 0.15)
				)
				(justify left bottom mirror)
			)
		)
		(property "Value" "C_1u_0402"
			(at 0 -1.4 90)
			(layer "B.Fab")
			(effects
				(font
					(size 0.7 0.7)
					(thickness 0.15)
				)
				(justify left bottom mirror)
			)
		)
		(property "Description" "SMD Multilayer Ceramic Capacitor, 1 µF, 10 V, 0402 [1005 Metric], ± 10%, X6S, C"
			(at 0 0 270)
			(layer "F.Fab")
			(hide yes)
			(effects
				(font
					(size 1.27 1.27)
					(thickness 0.15)
				)
			)
		)
		(property "Author" "Antmicro"
			(at 115.851 386.851 0)
			(layer "B.Fab")
			(hide yes)
			(effects
				(font
					(size 1 1)
					(thickness 0.15)
				)
				(justify mirror)
			)
		)
		(property "Dielectric" ""
			(at 115.851 386.851 0)
			(layer "B.Fab")
			(hide yes)
			(effects
				(font
					(size 1 1)
					(thickness 0.15)
				)
				(justify mirror)
			)
		)
		(property "License" "Apache-2.0"
			(at 115.851 386.851 0)
			(layer "B.Fab")
			(hide yes)
			(effects
				(font
					(size 1 1)
					(thickness 0.15)
				)
				(justify mirror)
			)
		)
		(property "MPN" "C1005X6S1A105K050BC"
			(at 115.851 386.851 0)
			(layer "B.Fab")
			(hide yes)
			(effects
				(font
					(size 1 1)
					(thickness 0.15)
				)
				(justify mirror)
			)
		)
		(property "Manufacturer" "TDK"
			(at 115.851 386.851 0)
			(layer "B.Fab")
			(hide yes)
			(effects
				(font
					(size 1 1)
					(thickness 0.15)
				)
				(justify mirror)
			)
		)
		(property "Val" "1u"
			(at 115.851 386.851 0)
			(layer "B.Fab")
			(hide yes)
			(effects
				(font
					(size 1 1)
					(thickness 0.15)
				)
				(justify mirror)
			)
		)
		(property "Voltage" ""
			(at 115.851 386.851 0)
			(layer "B.Fab")
			(hide yes)
			(effects
				(font
					(size 1 1)
					(thickness 0.15)
				)
				(justify mirror)
			)
		)
		(sheetname "SPI Flash + SD Card")
		(sheetfile "spi-flash.kicad_sch")
		(attr smd)
		(fp_rect
			(start -0.925 0.47)
			(end 0.925 -0.47)
			(stroke
				(width 0.05)
				(type default)
			)
			(fill no)
			(layer "B.CrtYd")
		)
		(fp_line
			(start -0.494 0.25)
			(end 0.504 0.25)
			(stroke
				(width 0.15)
				(type solid)
			)
			(layer "B.Fab")
		)
		(fp_line
			(start 0.504 0.25)
			(end 0.504 -0.248)
			(stroke
				(width 0.15)
				(type solid)
			)
			(layer "B.Fab")
		)
		(fp_line
			(start -0.494 -0.248)
			(end -0.494 0.25)
			(stroke
				(width 0.15)
				(type solid)
			)
			(layer "B.Fab")
		)
		(fp_line
			(start 0.504 -0.248)
			(end -0.494 -0.248)
			(stroke
				(width 0.15)
				(type solid)
			)
			(layer "B.Fab")
		)
		(pad "1" smd roundrect
			(at -0.48 0 270)
			(size 0.59 0.64)
			(layers "B.Cu" "B.Mask" "B.Paste")
			(roundrect_rratio 0.25)
			(net 1 "GND")
			(pintype "passive")
		)
		(pad "2" smd roundrect
			(at 0.48 0 270)
			(size 0.59 0.64)
			(layers "B.Cu" "B.Mask" "B.Paste")
			(roundrect_rratio 0.25)
			(net 24 "+3V3")
			(pintype "passive")
		)
	)
	(footprint "antmicro-footprints:R_0402_1005Metric"
		(layer "B.Cu")
		(at 163.1625 175.3 -90)
		(descr "Resistor SMD 0402")
		(tags "resistor SMD 0402")
		(property "Reference" "R317"
			(at 0.7 -0.4125 90)
			(layer "B.SilkS")
			(effects
				(font
					(size 0.7 0.7)
					(thickness 0.15)
				)
				(justify left bottom mirror)
			)
		)
		(property "Value" "R_0R_0402"
			(at 0 -1.4 90)
			(layer "B.Fab")
			(effects
				(font
					(size 0.7 0.7)
					(thickness 0.15)
				)
				(justify left bottom mirror)
			)
		)
		(property "Description" "SMD Chip Resistor, Jumper, 0 ohm, 100 mW, 0402 [1005 Metric], Thick Film, General Purpose"
			(at 0 0 270)
			(layer "F.Fab")
			(hide yes)
			(effects
				(font
					(size 1.27 1.27)
					(thickness 0.15)
				)
			)
		)
		(property "Author" "Antmicro"
			(at -12.1375 338.4625 0)
			(layer "B.Fab")
			(hide yes)
			(effects
				(font
					(size 1 1)
					(thickness 0.15)
				)
				(justify mirror)
			)
		)
		(property "Current" "1A"
			(at -12.1375 338.4625 0)
			(layer "B.Fab")
			(hide yes)
			(effects
				(font
					(size 1 1)
					(thickness 0.15)
				)
				(justify mirror)
			)
		)
		(property "DNP" "DNP"
			(at -12.1375 338.4625 0)
			(layer "B.Fab")
			(hide yes)
			(effects
				(font
					(size 1 1)
					(thickness 0.15)
				)
				(justify mirror)
			)
		)
		(property "License" "Apache-2.0"
			(at -12.1375 338.4625 0)
			(layer "B.Fab")
			(hide yes)
			(effects
				(font
					(size 1 1)
					(thickness 0.15)
				)
				(justify mirror)
			)
		)
		(property "MPN" "ERJ2GE0R00X"
			(at -12.1375 338.4625 0)
			(layer "B.Fab")
			(hide yes)
			(effects
				(font
					(size 1 1)
					(thickness 0.15)
				)
				(justify mirror)
			)
		)
		(property "Manufacturer" "Panasonic"
			(at -12.1375 338.4625 0)
			(layer "B.Fab")
			(hide yes)
			(effects
				(font
					(size 1 1)
					(thickness 0.15)
				)
				(justify mirror)
			)
		)
		(property "Tolerance" ""
			(at -12.1375 338.4625 0)
			(layer "B.Fab")
			(hide yes)
			(effects
				(font
					(size 1 1)
					(thickness 0.15)
				)
				(justify mirror)
			)
		)
		(property "Val" "0R"
			(at -12.1375 338.4625 0)
			(layer "B.Fab")
			(hide yes)
			(effects
				(font
					(size 1 1)
					(thickness 0.15)
				)
				(justify mirror)
			)
		)
		(property "dnp" ""
			(at -12.1375 338.4625 0)
			(layer "B.Fab")
			(hide yes)
			(effects
				(font
					(size 1 1)
					(thickness 0.15)
				)
				(justify mirror)
			)
		)
		(property "exclude_from_bom" ""
			(at -12.1375 338.4625 0)
			(layer "B.Fab")
			(hide yes)
			(effects
				(font
					(size 1 1)
					(thickness 0.15)
				)
				(justify mirror)
			)
		)
		(sheetname "DC-DC Converters")
		(sheetfile "dc-dc.kicad_sch")
		(attr smd exclude_from_bom)
		(fp_rect
			(start -0.925 0.47)
			(end 0.925 -0.47)
			(stroke
				(width 0.05)
				(type default)
			)
			(fill no)
			(layer "B.CrtYd")
		)
		(fp_rect
			(start -0.5 0.25)
			(end 0.5 -0.25)
			(stroke
				(width 0.15)
				(type solid)
			)
			(fill no)
			(layer "B.Fab")
		)
		(pad "1" smd roundrect
			(at -0.48 0 270)
			(size 0.59 0.64)
			(layers "B.Cu" "B.Mask" "B.Paste")
			(roundrect_rratio 0.25)
			(net 962 "/DC-DC Converters/FB3")
			(pintype "passive")
		)
		(pad "2" smd roundrect
			(at 0.48 0 270)
			(size 0.59 0.64)
			(layers "B.Cu" "B.Mask" "B.Paste")
			(roundrect_rratio 0.25)
			(net 1226 "/DC-DC Converters/SENSE_1V2_P")
			(pintype "passive")
		)
	)
	(footprint "antmicro-footprints:SC70-3"
		(layer "B.Cu")
		(at 256.901 172.44762 -90)
		(property "Reference" "Q18"
			(at 1.72738 -2.649 180)
			(layer "B.SilkS")
			(effects
				(font
					(size 0.7 0.7)
					(thickness 0.15)
				)
				(justify left bottom mirror)
			)
		)
		(property "Value" "BSS138PW"
			(at 0 -2.3 90)
			(layer "B.Fab")
			(effects
				(font
					(size 0.7 0.7)
					(thickness 0.15)
				)
				(justify left bottom mirror)
			)
		)
		(property "Description" "Power MOSFET, N Channel, 60 V, 320 mA, 0.9 ohm, SOT-323, Surface Mount"
			(at 0 0 270)
			(layer "F.Fab")
			(hide yes)
			(effects
				(font
					(size 1.27 1.27)
					(thickness 0.15)
				)
			)
		)
		(property "Author" "Antmicro"
			(at 84.45338 429.34862 0)
			(layer "B.Fab")
			(hide yes)
			(effects
				(font
					(size 1 1)
					(thickness 0.15)
				)
				(justify mirror)
			)
		)
		(property "License" "Apache-2.0"
			(at 84.45338 429.34862 0)
			(layer "B.Fab")
			(hide yes)
			(effects
				(font
					(size 1 1)
					(thickness 0.15)
				)
				(justify mirror)
			)
		)
		(property "MPN" "BSS138PW"
			(at 84.45338 429.34862 0)
			(layer "B.Fab")
			(hide yes)
			(effects
				(font
					(size 1 1)
					(thickness 0.15)
				)
				(justify mirror)
			)
		)
		(property "Manufacturer" "Nexperia"
			(at 84.45338 429.34862 0)
			(layer "B.Fab")
			(hide yes)
			(effects
				(font
					(size 1 1)
					(thickness 0.15)
				)
				(justify mirror)
			)
		)
		(sheetname "Power supply")
		(sheetfile "power-supply.kicad_sch")
		(attr smd)
		(fp_line
			(start -0.3 1)
			(end 0.627 0.999)
			(stroke
				(width 0.15)
				(type solid)
			)
			(layer "B.SilkS")
		)
		(fp_line
			(start 0.627 0.6)
			(end 0.627 0.999)
			(stroke
				(width 0.15)
				(type solid)
			)
			(layer "B.SilkS")
		)
		(fp_line
			(start 0.627 -0.6)
			(end 0.627 -1.001)
			(stroke
				(width 0.15)
				(type solid)
			)
			(layer "B.SilkS")
		)
		(fp_line
			(start -0.3 -1)
			(end 0.627 -1.001)
			(stroke
				(width 0.15)
				(type solid)
			)
			(layer "B.SilkS")
		)
		(fp_line
			(start -0.9 1.3)
			(end 0.9 1.3)
			(stroke
				(width 0.05)
				(type solid)
			)
			(layer "B.CrtYd")
		)
		(fp_line
			(start -0.9 1.3)
			(end -0.9 1)
			(stroke
				(width 0.05)
				(type solid)
			)
			(layer "B.CrtYd")
		)
		(fp_line
			(start 0.9 1.3)
			(end 0.9 0.4)
			(stroke
				(width 0.05)
				(type solid)
			)
			(layer "B.CrtYd")
		)
		(fp_line
			(start -0.9 1)
			(end -1.4 1)
			(stroke
				(width 0.05)
				(type solid)
			)
			(layer "B.CrtYd")
		)
		(fp_line
			(start 0.9 0.4)
			(end 1.4 0.4)
			(stroke
				(width 0.05)
				(type solid)
			)
			(layer "B.CrtYd")
		)
		(fp_line
			(start 1.4 0.4)
			(end 1.4 -0.4)
			(stroke
				(width 0.05)
				(type solid)
			)
			(layer "B.CrtYd")
		)
		(fp_line
			(start 0.9 -0.4)
			(end 0.9 -1.3)
			(stroke
				(width 0.05)
				(type solid)
			)
			(layer "B.CrtYd")
		)
		(fp_line
			(start 1.4 -0.4)
			(end 0.9 -0.4)
			(stroke
				(width 0.05)
				(type solid)
			)
			(layer "B.CrtYd")
		)
		(fp_line
			(start -1.4 -1)
			(end -1.4 1)
			(stroke
				(width 0.05)
				(type solid)
			)
			(layer "B.CrtYd")
		)
		(fp_line
			(start -0.9 -1)
			(end -1.4 -1)
			(stroke
				(width 0.05)
				(type solid)
			)
			(layer "B.CrtYd")
		)
		(fp_line
			(start -0.9 -1.3)
			(end -0.9 -1)
			(stroke
				(width 0.05)
				(type solid)
			)
			(layer "B.CrtYd")
		)
		(fp_line
			(start 0.9 -1.3)
			(end -0.9 -1.3)
			(stroke
				(width 0.05)
				(type solid)
			)
			(layer "B.CrtYd")
		)
		(fp_rect
			(start -0.623 0.999)
			(end 0.627 -1.001)
			(stroke
				(width 0.15)
				(type solid)
			)
			(fill no)
			(layer "B.Fab")
		)
		(pad "1" smd rect
			(at -1.051 0.65 180)
			(size 0.6 0.6)
			(layers "B.Cu" "B.Mask" "B.Paste")
			(net 889 "/Power supply/PG")
			(pinfunction "G")
			(pintype "passive")
		)
		(pad "2" smd rect
			(at -1.051 -0.65 180)
			(size 0.6 0.6)
			(layers "B.Cu" "B.Mask" "B.Paste")
			(net 699 "GNDD")
			(pinfunction "S")
			(pintype "passive")
		)
		(pad "3" smd rect
			(at 1.05 0 180)
			(size 0.6 0.6)
			(layers "B.Cu" "B.Mask" "B.Paste")
			(net 344 "Net-(Q18-D)")
			(pinfunction "D")
			(pintype "passive")
		)
	)
	(footprint "antmicro-footprints:C_0402_1005Metric"
		(layer "B.Cu")
		(at 157.65 146.5 -90)
		(descr "Capacitor SMD 0402")
		(tags "capacitor SMD 0402")
		(property "Reference" "C170"
			(at -1.025 3.475 90)
			(layer "B.SilkS")
			(effects
				(font
					(size 0.7 0.7)
					(thickness 0.15)
				)
				(justify left bottom mirror)
			)
		)
		(property "Value" "C_100n_0402"
			(at 0 -1.169 90)
			(layer "B.Fab")
			(effects
				(font
					(size 0.7 0.7)
					(thickness 0.15)
				)
				(justify left bottom mirror)
			)
		)
		(property "Description" "SMD Multilayer Ceramic Capacitor, 0.1 µF, 50 V, 0402 [1005 Metric], ± 10%, X5R, GRM Series"
			(at 0 0 270)
			(layer "F.Fab")
			(hide yes)
			(effects
				(font
					(size 1.27 1.27)
					(thickness 0.15)
				)
			)
		)
		(property "Author" "Antmicro"
			(at 11.15 304.15 0)
			(layer "B.Fab")
			(hide yes)
			(effects
				(font
					(size 1 1)
					(thickness 0.15)
				)
				(justify mirror)
			)
		)
		(property "Dielectric" "X5R"
			(at 11.15 304.15 0)
			(layer "B.Fab")
			(hide yes)
			(effects
				(font
					(size 1 1)
					(thickness 0.15)
				)
				(justify mirror)
			)
		)
		(property "License" "Apache-2.0"
			(at 11.15 304.15 0)
			(layer "B.Fab")
			(hide yes)
			(effects
				(font
					(size 1 1)
					(thickness 0.15)
				)
				(justify mirror)
			)
		)
		(property "MPN" "GRM155R61H104KE14D"
			(at 11.15 304.15 0)
			(layer "B.Fab")
			(hide yes)
			(effects
				(font
					(size 1 1)
					(thickness 0.15)
				)
				(justify mirror)
			)
		)
		(property "Manufacturer" "Murata"
			(at 11.15 304.15 0)
			(layer "B.Fab")
			(hide yes)
			(effects
				(font
					(size 1 1)
					(thickness 0.15)
				)
				(justify mirror)
			)
		)
		(property "Val" "100n"
			(at 11.15 304.15 0)
			(layer "B.Fab")
			(hide yes)
			(effects
				(font
					(size 1 1)
					(thickness 0.15)
				)
				(justify mirror)
			)
		)
		(property "Voltage" "50V"
			(at 11.15 304.15 0)
			(layer "B.Fab")
			(hide yes)
			(effects
				(font
					(size 1 1)
					(thickness 0.15)
				)
				(justify mirror)
			)
		)
		(sheetname "DRAM + SRAM")
		(sheetfile "ram.kicad_sch")
		(attr smd)
		(fp_rect
			(start -0.925 0.47)
			(end 0.925 -0.47)
			(stroke
				(width 0.05)
				(type default)
			)
			(fill no)
			(layer "B.CrtYd")
		)
		(fp_line
			(start -0.494 0.25)
			(end 0.504 0.25)
			(stroke
				(width 0.15)
				(type solid)
			)
			(layer "B.Fab")
		)
		(fp_line
			(start 0.504 0.25)
			(end 0.504 -0.248)
			(stroke
				(width 0.15)
				(type solid)
			)
			(layer "B.Fab")
		)
		(fp_line
			(start -0.494 -0.248)
			(end -0.494 0.25)
			(stroke
				(width 0.15)
				(type solid)
			)
			(layer "B.Fab")
		)
		(fp_line
			(start 0.504 -0.248)
			(end -0.494 -0.248)
			(stroke
				(width 0.15)
				(type solid)
			)
			(layer "B.Fab")
		)
		(pad "1" smd roundrect
			(at -0.48 0 270)
			(size 0.59 0.64)
			(layers "B.Cu" "B.Mask" "B.Paste")
			(roundrect_rratio 0.25)
			(net 7 "+0V675_VTT")
			(pintype "passive")
		)
		(pad "2" smd roundrect
			(at 0.48 0 270)
			(size 0.59 0.64)
			(layers "B.Cu" "B.Mask" "B.Paste")
			(roundrect_rratio 0.25)
			(net 25 "+1V35")
			(pintype "passive")
		)
	)
	(footprint "antmicro-footprints:C_0201"
		(layer "B.Cu")
		(at 188.000001 116.500001 180)
		(descr "Capacitor SMD 0201")
		(tags "capacitor SMD 0201")
		(property "Reference" "C142"
			(at 2.350001 0.425001 0)
			(layer "B.SilkS")
			(effects
				(font
					(size 0.7 0.7)
					(thickness 0.15)
				)
				(justify left bottom mirror)
			)
		)
		(property "Value" "C_100n_0201"
			(at 0 -1.4 0)
			(layer "B.Fab")
			(effects
				(font
					(size 0.7 0.7)
					(thickness 0.15)
				)
				(justify left bottom mirror)
			)
		)
		(property "Description" "SMD Multilayer Ceramic Capacitor, 0.1 µF, 6.3 V, 0201 [0603 Metric], ± 10%, X6S, CC Series"
			(at 0 0 180)
			(layer "F.Fab")
			(hide yes)
			(effects
				(font
					(size 1.27 1.27)
					(thickness 0.15)
				)
			)
		)
		(property "Author" "Antmicro"
			(at 376.000002 233.000002 0)
			(layer "B.Fab")
			(hide yes)
			(effects
				(font
					(size 1 1)
					(thickness 0.15)
				)
				(justify mirror)
			)
		)
		(property "Dielectric" ""
			(at 376.000002 233.000002 0)
			(layer "B.Fab")
			(hide yes)
			(effects
				(font
					(size 1 1)
					(thickness 0.15)
				)
				(justify mirror)
			)
		)
		(property "License" "Apache-2.0"
			(at 376.000002 233.000002 0)
			(layer "B.Fab")
			(hide yes)
			(effects
				(font
					(size 1 1)
					(thickness 0.15)
				)
				(justify mirror)
			)
		)
		(property "MPN" "CC0201KRX6S5BB104"
			(at 376.000002 233.000002 0)
			(layer "B.Fab")
			(hide yes)
			(effects
				(font
					(size 1 1)
					(thickness 0.15)
				)
				(justify mirror)
			)
		)
		(property "Manufacturer" "YAGEO"
			(at 376.000002 233.000002 0)
			(layer "B.Fab")
			(hide yes)
			(effects
				(font
					(size 1 1)
					(thickness 0.15)
				)
				(justify mirror)
			)
		)
		(property "Val" "100n"
			(at 376.000002 233.000002 0)
			(layer "B.Fab")
			(hide yes)
			(effects
				(font
					(size 1 1)
					(thickness 0.15)
				)
				(justify mirror)
			)
		)
		(property "Voltage" ""
			(at 376.000002 233.000002 0)
			(layer "B.Fab")
			(hide yes)
			(effects
				(font
					(size 1 1)
					(thickness 0.15)
				)
				(justify mirror)
			)
		)
		(sheetname "FPGA supply")
		(sheetfile "fpga-supply.kicad_sch")
		(attr smd)
		(fp_rect
			(start -0.7 0.35)
			(end 0.7 -0.35)
			(stroke
				(width 0.05)
				(type default)
			)
			(fill no)
			(layer "B.CrtYd")
		)
		(fp_rect
			(start 0.3 -0.15)
			(end -0.301 0.149)
			(stroke
				(width 0.15)
				(type solid)
			)
			(fill no)
			(layer "B.Fab")
		)
		(pad "" smd roundrect
			(at -0.349 0.002 180)
			(size 0.318 0.36)
			(layers "B.Paste")
			(roundrect_rratio 0.25)
		)
		(pad "" smd roundrect
			(at 0.341 0.002 180)
			(size 0.318 0.36)
			(layers "B.Paste")
			(roundrect_rratio 0.25)
		)
		(pad "1" smd roundrect
			(at -0.321 0.002 180)
			(size 0.46 0.4)
			(layers "B.Cu" "B.Mask")
			(roundrect_rratio 0.25)
			(net 1 "GND")
			(pintype "passive")
		)
		(pad "2" smd roundrect
			(at 0.32 0.002 180)
			(size 0.46 0.4)
			(layers "B.Cu" "B.Mask")
			(roundrect_rratio 0.25)
			(net 8 "+1V2_MGTAVTT")
			(pintype "passive")
		)
	)
)
